(kicad_pcb
	(version 20260206)
	(generator "pcbnew")
	(generator_version "10.0")
	(general
		(thickness 1.6)
		(legacy_teardrops no)
	)
	(paper "A4")
	(title_block
		(title "01162023_DA0F0TEBIF0_F0T_Expander_BD_F_brd_V02_OCP.brd")
		(comment 1 "Grand Teton / footprints 3295-3300 of 9728")
	)
	(layers
		(0 "F.Cu" signal "TOP")
		(4 "In1.Cu" signal "GND")
		(6 "In2.Cu" signal "VCC")
		(8 "In3.Cu" signal "VCC1")
		(10 "In4.Cu" signal "GND1")
		(12 "In5.Cu" signal "IN1")
		(14 "In6.Cu" signal "GND2")
		(16 "In7.Cu" signal "IN2")
		(18 "In8.Cu" signal "GND3")
		(20 "In9.Cu" signal "IN3")
		(22 "In10.Cu" signal "GND4")
		(24 "In11.Cu" signal "IN4")
		(26 "In12.Cu" signal "GND5")
		(28 "In13.Cu" signal "IN5")
		(30 "In14.Cu" signal "GND6")
		(32 "In15.Cu" signal "IN6")
		(34 "In16.Cu" signal "GND7")
		(2 "B.Cu" signal "BOTTOM")
		(9 "F.Adhes" user "F.Adhesive")
		(11 "B.Adhes" user "B.Adhesive")
		(13 "F.Paste" user "Package Geometry/Pastemask Top")
		(15 "B.Paste" user "Package Geometry/Pastemask Bottom")
		(5 "F.SilkS" user "Ref Des/Silkscreen Top")
		(7 "B.SilkS" user "Ref Des/Silkscreen Bottom")
		(1 "F.Mask" user "Board Geometry/Soldermask Top")
		(3 "B.Mask" user "Board Geometry/Soldermask Bottom")
		(17 "Dwgs.User" user "User.Drawings")
		(19 "Cmts.User" user "User.Comments")
		(21 "Eco1.User" user "User.Eco1")
		(23 "Eco2.User" user "User.Eco2")
		(25 "Edge.Cuts" user "Board Geometry/Outline")
		(27 "Margin" user)
		(31 "F.CrtYd" user "Package Geometry/Place Bound Top")
		(29 "B.CrtYd" user "Package Geometry/Place Bound Bottom")
		(35 "F.Fab" user "Ref Des/Assembly Top")
		(33 "B.Fab" user "Ref Des/Assembly Bottom")
	)
	(footprint ""
		(layer "F.Cu")
		(at 343.662 -205.232 -90)
		(property "Reference" "R4139"
			(at 0 0 270)
			(layer "F.SilkS")
			(hide yes)
			(effects
				(font
					(size 1.27 1.27)
				)
			)
		)
		(property "Value" ""
			(at 0 0 270)
			(layer "F.Fab")
			(effects
				(font
					(size 1.27 1.27)
				)
			)
		)
		(duplicate_pad_numbers_are_jumpers no)
		(fp_line
			(start -0.7874 0.4064)
			(end -0.7874 -0.4064)
			(stroke
				(width 0.1524)
				(type default)
			)
			(layer "F.SilkS")
		)
		(fp_line
			(start 0.7874 0.4064)
			(end -0.7874 0.4064)
			(stroke
				(width 0.1524)
				(type default)
			)
			(layer "F.SilkS")
		)
		(fp_line
			(start -0.7874 -0.4064)
			(end 0.7874 -0.4064)
			(stroke
				(width 0.1524)
				(type default)
			)
			(layer "F.SilkS")
		)
		(fp_line
			(start 0.7874 -0.4064)
			(end 0.7874 0.4064)
			(stroke
				(width 0.1524)
				(type default)
			)
			(layer "F.SilkS")
		)
		(fp_line
			(start -0.67945 0.3048)
			(end -0.67945 -0.305054)
			(stroke
				(width 0.1)
				(type default)
			)
			(layer "F.Fab")
		)
		(fp_line
			(start -0.12065 0.3048)
			(end -0.67945 0.3048)
			(stroke
				(width 0.1)
				(type default)
			)
			(layer "F.Fab")
		)
		(fp_line
			(start 0.120396 0.3048)
			(end 0.120396 0.2794)
			(stroke
				(width 0.1)
				(type default)
			)
			(layer "F.Fab")
		)
		(fp_line
			(start 0.67945 0.3048)
			(end 0.120396 0.3048)
			(stroke
				(width 0.1)
				(type default)
			)
			(layer "F.Fab")
		)
		(fp_line
			(start -0.12065 0.2794)
			(end -0.12065 0.3048)
			(stroke
				(width 0.1)
				(type default)
			)
			(layer "F.Fab")
		)
		(fp_line
			(start 0.120396 0.2794)
			(end -0.12065 0.2794)
			(stroke
				(width 0.1)
				(type default)
			)
			(layer "F.Fab")
		)
		(fp_line
			(start -0.12065 -0.2794)
			(end 0.12065 -0.2794)
			(stroke
				(width 0.1)
				(type default)
			)
			(layer "F.Fab")
		)
		(fp_line
			(start 0.12065 -0.2794)
			(end 0.12065 -0.3048)
			(stroke
				(width 0.1)
				(type default)
			)
			(layer "F.Fab")
		)
		(fp_line
			(start 0.12065 -0.3048)
			(end 0.67945 -0.3048)
			(stroke
				(width 0.1)
				(type default)
			)
			(layer "F.Fab")
		)
		(fp_line
			(start 0.67945 -0.3048)
			(end 0.67945 0.3048)
			(stroke
				(width 0.1)
				(type default)
			)
			(layer "F.Fab")
		)
		(fp_line
			(start -0.67945 -0.305054)
			(end -0.12065 -0.305054)
			(stroke
				(width 0.1)
				(type default)
			)
			(layer "F.Fab")
		)
		(fp_line
			(start -0.12065 -0.305054)
			(end -0.12065 -0.2794)
			(stroke
				(width 0.1)
				(type default)
			)
			(layer "F.Fab")
		)
		(pad "1" smd circle
			(at -0.40005 0 270)
			(size 0 0)
			(layers "F.Cu" "F.Mask" "F.Paste")
			(net "SSD14_PWR_EN")
		)
		(pad "2" smd circle
			(at 0.40005 0 270)
			(size 0 0)
			(layers "F.Cu" "F.Mask" "F.Paste")
			(net "SSD14_PWR_EN_R")
		)
	)
	(footprint ""
		(layer "F.Cu")
		(at 135.571738 -25.342342 -90)
		(property "Reference" "R421"
			(at 0 0 270)
			(layer "F.SilkS")
			(hide yes)
			(effects
				(font
					(size 1.27 1.27)
				)
			)
		)
		(property "Value" ""
			(at 0 0 270)
			(layer "F.Fab")
			(effects
				(font
					(size 1.27 1.27)
				)
			)
		)
		(duplicate_pad_numbers_are_jumpers no)
		(fp_line
			(start -0.7874 0.4064)
			(end -0.7874 -0.4064)
			(stroke
				(width 0.1524)
				(type default)
			)
			(layer "F.SilkS")
		)
		(fp_line
			(start 0.7874 0.4064)
			(end -0.7874 0.4064)
			(stroke
				(width 0.1524)
				(type default)
			)
			(layer "F.SilkS")
		)
		(fp_line
			(start -0.7874 -0.4064)
			(end 0.7874 -0.4064)
			(stroke
				(width 0.1524)
				(type default)
			)
			(layer "F.SilkS")
		)
		(fp_line
			(start 0.7874 -0.4064)
			(end 0.7874 0.4064)
			(stroke
				(width 0.1524)
				(type default)
			)
			(layer "F.SilkS")
		)
		(fp_line
			(start -0.67945 0.3048)
			(end -0.67945 -0.305054)
			(stroke
				(width 0.1)
				(type default)
			)
			(layer "F.Fab")
		)
		(fp_line
			(start -0.12065 0.3048)
			(end -0.67945 0.3048)
			(stroke
				(width 0.1)
				(type default)
			)
			(layer "F.Fab")
		)
		(fp_line
			(start 0.120396 0.3048)
			(end 0.120396 0.2794)
			(stroke
				(width 0.1)
				(type default)
			)
			(layer "F.Fab")
		)
		(fp_line
			(start 0.67945 0.3048)
			(end 0.120396 0.3048)
			(stroke
				(width 0.1)
				(type default)
			)
			(layer "F.Fab")
		)
		(fp_line
			(start -0.12065 0.2794)
			(end -0.12065 0.3048)
			(stroke
				(width 0.1)
				(type default)
			)
			(layer "F.Fab")
		)
		(fp_line
			(start 0.120396 0.2794)
			(end -0.12065 0.2794)
			(stroke
				(width 0.1)
				(type default)
			)
			(layer "F.Fab")
		)
		(fp_line
			(start -0.12065 -0.2794)
			(end 0.12065 -0.2794)
			(stroke
				(width 0.1)
				(type default)
			)
			(layer "F.Fab")
		)
		(fp_line
			(start 0.12065 -0.2794)
			(end 0.12065 -0.3048)
			(stroke
				(width 0.1)
				(type default)
			)
			(layer "F.Fab")
		)
		(fp_line
			(start 0.12065 -0.3048)
			(end 0.67945 -0.3048)
			(stroke
				(width 0.1)
				(type default)
			)
			(layer "F.Fab")
		)
		(fp_line
			(start 0.67945 -0.3048)
			(end 0.67945 0.3048)
			(stroke
				(width 0.1)
				(type default)
			)
			(layer "F.Fab")
		)
		(fp_line
			(start -0.67945 -0.305054)
			(end -0.12065 -0.305054)
			(stroke
				(width 0.1)
				(type default)
			)
			(layer "F.Fab")
		)
		(fp_line
			(start -0.12065 -0.305054)
			(end -0.12065 -0.2794)
			(stroke
				(width 0.1)
				(type default)
			)
			(layer "F.Fab")
		)
		(pad "1" smd circle
			(at -0.40005 0 270)
			(size 0 0)
			(layers "F.Cu" "F.Mask" "F.Paste")
			(net "P3V3_SSD4")
		)
		(pad "2" smd circle
			(at 0.40005 0 270)
			(size 0 0)
			(layers "F.Cu" "F.Mask" "F.Paste")
			(net "DUALPORT_N_SSD4")
		)
	)
	(footprint ""
		(layer "F.Cu")
		(at 320.354452 -217.039698 180)
		(property "Reference" "D20"
			(at 3.743452 -0.023368 0)
			(unlocked yes)
			(layer "F.SilkS")
			(effects
				(font
					(size 0.7874 0.5842)
					(thickness 0.1524)
				)
				(justify left)
			)
		)
		(property "Value" ""
			(at 0 0 180)
			(layer "F.Fab")
			(effects
				(font
					(size 1.27 1.27)
				)
			)
		)
		(duplicate_pad_numbers_are_jumpers no)
		(fp_line
			(start 1.16078 0.4826)
			(end -0.64008 0.4826)
			(stroke
				(width 0.1524)
				(type default)
			)
			(layer "F.SilkS")
		)
		(fp_line
			(start 1.16078 -0.4826)
			(end 1.16078 0.4826)
			(stroke
				(width 0.1524)
				(type default)
			)
			(layer "F.SilkS")
		)
		(fp_line
			(start 1.03378 0.4826)
			(end -0.79248 0.4826)
			(stroke
				(width 0.1524)
				(type default)
			)
			(layer "F.SilkS")
		)
		(fp_line
			(start 1.03378 -0.4826)
			(end 1.03378 0.4826)
			(stroke
				(width 0.1524)
				(type default)
			)
			(layer "F.SilkS")
		)
		(fp_line
			(start 0.90678 0.4826)
			(end -0.90678 0.4826)
			(stroke
				(width 0.1524)
				(type default)
			)
			(layer "F.SilkS")
		)
		(fp_line
			(start 0.90678 -0.4826)
			(end 0.90678 0.4826)
			(stroke
				(width 0.1524)
				(type default)
			)
			(layer "F.SilkS")
		)
		(fp_line
			(start -0.64008 -0.4826)
			(end 1.16078 -0.4826)
			(stroke
				(width 0.1524)
				(type default)
			)
			(layer "F.SilkS")
		)
		(fp_line
			(start -0.79248 -0.4826)
			(end 1.03378 -0.4826)
			(stroke
				(width 0.1524)
				(type default)
			)
			(layer "F.SilkS")
		)
		(fp_line
			(start -0.89408 -0.4826)
			(end 0.90678 -0.4826)
			(stroke
				(width 0.1524)
				(type default)
			)
			(layer "F.SilkS")
		)
		(fp_line
			(start -0.90678 0.4826)
			(end -0.90678 -0.4699)
			(stroke
				(width 0.1524)
				(type default)
			)
			(layer "F.SilkS")
		)
		(fp_line
			(start 0.499872 0.249936)
			(end -0.499872 0.249936)
			(stroke
				(width 0.1)
				(type default)
			)
			(layer "F.Fab")
		)
		(fp_line
			(start 0.499872 -0.249936)
			(end 0.499872 0.249936)
			(stroke
				(width 0.1)
				(type default)
			)
			(layer "F.Fab")
		)
		(fp_line
			(start -0.499872 0.249936)
			(end -0.499872 -0.249936)
			(stroke
				(width 0.1)
				(type default)
			)
			(layer "F.Fab")
		)
		(fp_line
			(start -0.499872 -0.249936)
			(end 0.499872 -0.249936)
			(stroke
				(width 0.1)
				(type default)
			)
			(layer "F.Fab")
		)
		(pad "A" smd rect
			(at -0.47498 0 180)
			(size 0.6096 0.7112)
			(layers "F.Cu" "F.Mask" "F.Paste")
			(net "LED_POSTCODE_R_7")
		)
		(pad "C" smd rect
			(at 0.47498 0 180)
			(size 0.6096 0.7112)
			(layers "F.Cu" "F.Mask" "F.Paste")
			(net "FPGA_DEBUG_LED_R_N")
		)
	)
	(footprint ""
		(layer "F.Cu")
		(at 78.584044 -29.222954 -90)
		(property "Reference" "PC679"
			(at 0 0 270)
			(layer "F.SilkS")
			(hide yes)
			(effects
				(font
					(size 1.27 1.27)
				)
			)
		)
		(property "Value" ""
			(at 0 0 270)
			(layer "F.Fab")
			(effects
				(font
					(size 1.27 1.27)
				)
			)
		)
		(duplicate_pad_numbers_are_jumpers no)
		(fp_line
			(start -0.7874 0.4064)
			(end -0.7874 -0.4064)
			(stroke
				(width 0.1524)
				(type default)
			)
			(layer "F.SilkS")
		)
		(fp_line
			(start 0.7874 0.4064)
			(end -0.7874 0.4064)
			(stroke
				(width 0.1524)
				(type default)
			)
			(layer "F.SilkS")
		)
		(fp_line
			(start -0.7874 -0.4064)
			(end 0.7874 -0.4064)
			(stroke
				(width 0.1524)
				(type default)
			)
			(layer "F.SilkS")
		)
		(fp_line
			(start 0.7874 -0.4064)
			(end 0.7874 0.4064)
			(stroke
				(width 0.1524)
				(type default)
			)
			(layer "F.SilkS")
		)
		(fp_line
			(start -0.67945 0.3048)
			(end -0.67945 -0.305054)
			(stroke
				(width 0.1)
				(type default)
			)
			(layer "F.Fab")
		)
		(fp_line
			(start -0.12065 0.3048)
			(end -0.67945 0.3048)
			(stroke
				(width 0.1)
				(type default)
			)
			(layer "F.Fab")
		)
		(fp_line
			(start 0.120396 0.3048)
			(end 0.120396 0.2794)
			(stroke
				(width 0.1)
				(type default)
			)
			(layer "F.Fab")
		)
		(fp_line
			(start 0.67945 0.3048)
			(end 0.120396 0.3048)
			(stroke
				(width 0.1)
				(type default)
			)
			(layer "F.Fab")
		)
		(fp_line
			(start -0.12065 0.2794)
			(end -0.12065 0.3048)
			(stroke
				(width 0.1)
				(type default)
			)
			(layer "F.Fab")
		)
		(fp_line
			(start 0.120396 0.2794)
			(end -0.12065 0.2794)
			(stroke
				(width 0.1)
				(type default)
			)
			(layer "F.Fab")
		)
		(fp_line
			(start -0.12065 -0.2794)
			(end 0.12065 -0.2794)
			(stroke
				(width 0.1)
				(type default)
			)
			(layer "F.Fab")
		)
		(fp_line
			(start 0.12065 -0.2794)
			(end 0.12065 -0.3048)
			(stroke
				(width 0.1)
				(type default)
			)
			(layer "F.Fab")
		)
		(fp_line
			(start 0.12065 -0.3048)
			(end 0.67945 -0.3048)
			(stroke
				(width 0.1)
				(type default)
			)
			(layer "F.Fab")
		)
		(fp_line
			(start 0.67945 -0.3048)
			(end 0.67945 0.3048)
			(stroke
				(width 0.1)
				(type default)
			)
			(layer "F.Fab")
		)
		(fp_line
			(start -0.67945 -0.305054)
			(end -0.12065 -0.305054)
			(stroke
				(width 0.1)
				(type default)
			)
			(layer "F.Fab")
		)
		(fp_line
			(start -0.12065 -0.305054)
			(end -0.12065 -0.2794)
			(stroke
				(width 0.1)
				(type default)
			)
			(layer "F.Fab")
		)
		(pad "1" smd circle
			(at -0.40005 0 270)
			(size 0 0)
			(layers "F.Cu" "F.Mask" "F.Paste")
			(net "P3V3_AUX")
		)
		(pad "2" smd circle
			(at 0.40005 0 270)
			(size 0 0)
			(layers "F.Cu" "F.Mask" "F.Paste")
			(net "GND")
		)
	)
	(footprint ""
		(layer "F.Cu")
		(at 447.275712 -123.795028)
		(property "Reference" "C2884"
			(at 0 0 0)
			(layer "F.SilkS")
			(hide yes)
			(effects
				(font
					(size 1.27 1.27)
				)
			)
		)
		(property "Value" ""
			(at 0 0 0)
			(layer "F.Fab")
			(effects
				(font
					(size 1.27 1.27)
				)
			)
		)
		(duplicate_pad_numbers_are_jumpers no)
		(fp_line
			(start -0.7874 -0.4064)
			(end 0.7874 -0.4064)
			(stroke
				(width 0.1524)
				(type default)
			)
			(layer "F.SilkS")
		)
		(fp_line
			(start -0.7874 0.4064)
			(end -0.7874 -0.4064)
			(stroke
				(width 0.1524)
				(type default)
			)
			(layer "F.SilkS")
		)
		(fp_line
			(start 0.7874 -0.4064)
			(end 0.7874 0.4064)
			(stroke
				(width 0.1524)
				(type default)
			)
			(layer "F.SilkS")
		)
		(fp_line
			(start 0.7874 0.4064)
			(end -0.7874 0.4064)
			(stroke
				(width 0.1524)
				(type default)
			)
			(layer "F.SilkS")
		)
		(fp_line
			(start -0.67945 -0.305054)
			(end -0.12065 -0.305054)
			(stroke
				(width 0.1)
				(type default)
			)
			(layer "F.Fab")
		)
		(fp_line
			(start -0.67945 0.3048)
			(end -0.67945 -0.305054)
			(stroke
				(width 0.1)
				(type default)
			)
			(layer "F.Fab")
		)
		(fp_line
			(start -0.12065 -0.305054)
			(end -0.12065 -0.2794)
			(stroke
				(width 0.1)
				(type default)
			)
			(layer "F.Fab")
		)
		(fp_line
			(start -0.12065 -0.2794)
			(end 0.12065 -0.2794)
			(stroke
				(width 0.1)
				(type default)
			)
			(layer "F.Fab")
		)
		(fp_line
			(start -0.12065 0.2794)
			(end -0.12065 0.3048)
			(stroke
				(width 0.1)
				(type default)
			)
			(layer "F.Fab")
		)
		(fp_line
			(start -0.12065 0.3048)
			(end -0.67945 0.3048)
			(stroke
				(width 0.1)
				(type default)
			)
			(layer "F.Fab")
		)
		(fp_line
			(start 0.120396 0.2794)
			(end -0.12065 0.2794)
			(stroke
				(width 0.1)
				(type default)
			)
			(layer "F.Fab")
		)
		(fp_line
			(start 0.120396 0.3048)
			(end 0.120396 0.2794)
			(stroke
				(width 0.1)
				(type default)
			)
			(layer "F.Fab")
		)
		(fp_line
			(start 0.12065 -0.3048)
			(end 0.67945 -0.3048)
			(stroke
				(width 0.1)
				(type default)
			)
			(layer "F.Fab")
		)
		(fp_line
			(start 0.12065 -0.2794)
			(end 0.12065 -0.3048)
			(stroke
				(width 0.1)
				(type default)
			)
			(layer "F.Fab")
		)
		(fp_line
			(start 0.67945 -0.3048)
			(end 0.67945 0.3048)
			(stroke
				(width 0.1)
				(type default)
			)
			(layer "F.Fab")
		)
		(fp_line
			(start 0.67945 0.3048)
			(end 0.120396 0.3048)
			(stroke
				(width 0.1)
				(type default)
			)
			(layer "F.Fab")
		)
		(pad "1" smd circle
			(at -0.40005 0)
			(size 0 0)
			(layers "F.Cu" "F.Mask" "F.Paste")
			(net "HP_NIC7_EN")
		)
		(pad "2" smd circle
			(at 0.40005 0)
			(size 0 0)
			(layers "F.Cu" "F.Mask" "F.Paste")
			(net "GND")
		)
	)
	(footprint ""
		(layer "F.Cu")
		(at 238.85271 -156.288994 -90)
		(property "Reference" "PR7021"
			(at 0 0 270)
			(layer "F.SilkS")
			(hide yes)
			(effects
				(font
					(size 1.27 1.27)
				)
			)
		)
		(property "Value" ""
			(at 0 0 270)
			(layer "F.Fab")
			(effects
				(font
					(size 1.27 1.27)
				)
			)
		)
		(duplicate_pad_numbers_are_jumpers no)
		(fp_line
			(start -0.7874 0.4064)
			(end -0.7874 -0.4064)
			(stroke
				(width 0.1524)
				(type default)
			)
			(layer "F.SilkS")
		)
		(fp_line
			(start 0.7874 0.4064)
			(end -0.7874 0.4064)
			(stroke
				(width 0.1524)
				(type default)
			)
			(layer "F.SilkS")
		)
		(fp_line
			(start -0.7874 -0.4064)
			(end 0.7874 -0.4064)
			(stroke
				(width 0.1524)
				(type default)
			)
			(layer "F.SilkS")
		)
		(fp_line
			(start 0.7874 -0.4064)
			(end 0.7874 0.4064)
			(stroke
				(width 0.1524)
				(type default)
			)
			(layer "F.SilkS")
		)
		(fp_line
			(start -0.67945 0.3048)
			(end -0.67945 -0.305054)
			(stroke
				(width 0.1)
				(type default)
			)
			(layer "F.Fab")
		)
		(fp_line
			(start -0.12065 0.3048)
			(end -0.67945 0.3048)
			(stroke
				(width 0.1)
				(type default)
			)
			(layer "F.Fab")
		)
		(fp_line
			(start 0.120396 0.3048)
			(end 0.120396 0.2794)
			(stroke
				(width 0.1)
				(type default)
			)
			(layer "F.Fab")
		)
		(fp_line
			(start 0.67945 0.3048)
			(end 0.120396 0.3048)
			(stroke
				(width 0.1)
				(type default)
			)
			(layer "F.Fab")
		)
		(fp_line
			(start -0.12065 0.2794)
			(end -0.12065 0.3048)
			(stroke
				(width 0.1)
				(type default)
			)
			(layer "F.Fab")
		)
		(fp_line
			(start 0.120396 0.2794)
			(end -0.12065 0.2794)
			(stroke
				(width 0.1)
				(type default)
			)
			(layer "F.Fab")
		)
		(fp_line
			(start -0.12065 -0.2794)
			(end 0.12065 -0.2794)
			(stroke
				(width 0.1)
				(type default)
			)
			(layer "F.Fab")
		)
		(fp_line
			(start 0.12065 -0.2794)
			(end 0.12065 -0.3048)
			(stroke
				(width 0.1)
				(type default)
			)
			(layer "F.Fab")
		)
		(fp_line
			(start 0.12065 -0.3048)
			(end 0.67945 -0.3048)
			(stroke
				(width 0.1)
				(type default)
			)
			(layer "F.Fab")
		)
		(fp_line
			(start 0.67945 -0.3048)
			(end 0.67945 0.3048)
			(stroke
				(width 0.1)
				(type default)
			)
			(layer "F.Fab")
		)
		(fp_line
			(start -0.67945 -0.305054)
			(end -0.12065 -0.305054)
			(stroke
				(width 0.1)
				(type default)
			)
			(layer "F.Fab")
		)
		(fp_line
			(start -0.12065 -0.305054)
			(end -0.12065 -0.2794)
			(stroke
				(width 0.1)
				(type default)
			)
			(layer "F.Fab")
		)
		(pad "1" smd circle
			(at -0.40005 0 270)
			(size 0 0)
			(layers "F.Cu" "F.Mask" "F.Paste")
			(net "P12V_NIC4_CO_OV_FB")
		)
		(pad "2" smd circle
			(at 0.40005 0 270)
			(size 0 0)
			(layers "F.Cu" "F.Mask" "F.Paste")
			(net "P12V_NIC4_R")
		)
	)
)
